;LEADER: 12 
;HEADER: 
;CODE  : ASCII 
;FILE  : 9332_F0TG_MB_C_V02_0417_0820-bd-1-11.drl for backdrilling ... from layer TOP to layer GND4
;DESIGN: 9332_F0TG_MB_C_V02_0417_0820.brd
;MUST-NOT-CUT-LAYER = IN4,  MAX_DRILL_DEPTH = 61.70 MILS,  MFG_STUB_LENGTH = 0.00 MILS
;   BackdrillSize 1. = 17.000000 Tolerance = +0.000000/-0.000000 NON_PLATED MILS Quantity = 44
%
G90
X0306136Y1602380
R08X-0012060
X0378496Y1602380
R05X-0012060
X0197596Y1602380
X0302736Y1602380
X0290676Y1602380
R07X-0012060
X0375096Y1602380
R05X-0012060
X0194196Y1602380
X1729557Y-0032512
X1539134Y-0032512
X1729557Y-0035912
X1539134Y-0035912
X1177404Y0008289
X0842320Y0008289
X1177404Y0011689
X0842320Y0011689
X0806500Y0960966
X1782642Y0960965
X0090965Y0960966
X1067107Y0960965
M30
